(kicad_pcb
	(version 20260206)
	(generator "pcbnew")
	(generator_version "10.0")
	(general
		(thickness 1.6)
		(legacy_teardrops no)
	)
	(paper "A4")
	(title_block
		(title "04192023_DAF0TMB3IC0_F0TG_MB_C_brd_V02_OCP.brd")
		(comment 1 "Grand Teton / footprints 4912-4918 of 8354")
	)
	(layers
		(0 "F.Cu" signal "TOP")
		(4 "In1.Cu" signal "GND")
		(6 "In2.Cu" signal "IN1")
		(8 "In3.Cu" signal "GND1")
		(10 "In4.Cu" signal "IN2")
		(12 "In5.Cu" signal "GND2")
		(14 "In6.Cu" signal "IN3")
		(16 "In7.Cu" signal "GND3")
		(18 "In8.Cu" signal "VCC")
		(20 "In9.Cu" signal "VCC1")
		(22 "In10.Cu" signal "GND4")
		(24 "In11.Cu" signal "IN4")
		(26 "In12.Cu" signal "GND5")
		(28 "In13.Cu" signal "IN5")
		(30 "In14.Cu" signal "GND6")
		(32 "In15.Cu" signal "IN6")
		(34 "In16.Cu" signal "GND7")
		(2 "B.Cu" signal "BOTTOM")
		(9 "F.Adhes" user "F.Adhesive")
		(11 "B.Adhes" user "B.Adhesive")
		(13 "F.Paste" user "Package Geometry/Pastemask Top")
		(15 "B.Paste" user "Package Geometry/Pastemask Bottom")
		(5 "F.SilkS" user "Ref Des/Silkscreen Top")
		(7 "B.SilkS" user "Ref Des/Silkscreen Bottom")
		(1 "F.Mask" user "Board Geometry/Soldermask Top")
		(3 "B.Mask" user "Board Geometry/Soldermask Bottom")
		(17 "Dwgs.User" user "User.Drawings")
		(19 "Cmts.User" user "User.Comments")
		(21 "Eco1.User" user "User.Eco1")
		(23 "Eco2.User" user "User.Eco2")
		(25 "Edge.Cuts" user "Board Geometry/Outline")
		(27 "Margin" user)
		(31 "F.CrtYd" user "Package Geometry/Place Bound Top")
		(29 "B.CrtYd" user "Package Geometry/Place Bound Bottom")
		(35 "F.Fab" user "Ref Des/Assembly Top")
		(33 "B.Fab" user "Ref Des/Assembly Bottom")
	)
	(footprint ""
		(layer "F.Cu")
		(at 449.443602 -420.99611 180)
		(property "Reference" "R652"
			(at 0 0 180)
			(layer "F.SilkS")
			(hide yes)
			(effects
				(font
					(size 1.27 1.27)
				)
			)
		)
		(property "Value" ""
			(at 0 0 180)
			(layer "F.Fab")
			(effects
				(font
					(size 1.27 1.27)
				)
			)
		)
		(duplicate_pad_numbers_are_jumpers no)
		(fp_line
			(start 0.7874 0.4064)
			(end -0.7874 0.4064)
			(stroke
				(width 0.1524)
				(type default)
			)
			(layer "F.SilkS")
		)
		(fp_line
			(start 0.7874 -0.4064)
			(end 0.7874 0.4064)
			(stroke
				(width 0.1524)
				(type default)
			)
			(layer "F.SilkS")
		)
		(fp_line
			(start -0.7874 0.4064)
			(end -0.7874 -0.4064)
			(stroke
				(width 0.1524)
				(type default)
			)
			(layer "F.SilkS")
		)
		(fp_line
			(start -0.7874 -0.4064)
			(end 0.7874 -0.4064)
			(stroke
				(width 0.1524)
				(type default)
			)
			(layer "F.SilkS")
		)
		(fp_line
			(start 0.67945 0.3048)
			(end 0.120396 0.3048)
			(stroke
				(width 0.1)
				(type default)
			)
			(layer "F.Fab")
		)
		(fp_line
			(start 0.67945 -0.3048)
			(end 0.67945 0.3048)
			(stroke
				(width 0.1)
				(type default)
			)
			(layer "F.Fab")
		)
		(fp_line
			(start 0.12065 -0.2794)
			(end 0.12065 -0.3048)
			(stroke
				(width 0.1)
				(type default)
			)
			(layer "F.Fab")
		)
		(fp_line
			(start 0.12065 -0.3048)
			(end 0.67945 -0.3048)
			(stroke
				(width 0.1)
				(type default)
			)
			(layer "F.Fab")
		)
		(fp_line
			(start 0.120396 0.3048)
			(end 0.120396 0.2794)
			(stroke
				(width 0.1)
				(type default)
			)
			(layer "F.Fab")
		)
		(fp_line
			(start 0.120396 0.2794)
			(end -0.12065 0.2794)
			(stroke
				(width 0.1)
				(type default)
			)
			(layer "F.Fab")
		)
		(fp_line
			(start -0.12065 0.3048)
			(end -0.67945 0.3048)
			(stroke
				(width 0.1)
				(type default)
			)
			(layer "F.Fab")
		)
		(fp_line
			(start -0.12065 0.2794)
			(end -0.12065 0.3048)
			(stroke
				(width 0.1)
				(type default)
			)
			(layer "F.Fab")
		)
		(fp_line
			(start -0.12065 -0.2794)
			(end 0.12065 -0.2794)
			(stroke
				(width 0.1)
				(type default)
			)
			(layer "F.Fab")
		)
		(fp_line
			(start -0.12065 -0.305054)
			(end -0.12065 -0.2794)
			(stroke
				(width 0.1)
				(type default)
			)
			(layer "F.Fab")
		)
		(fp_line
			(start -0.67945 0.3048)
			(end -0.67945 -0.305054)
			(stroke
				(width 0.1)
				(type default)
			)
			(layer "F.Fab")
		)
		(fp_line
			(start -0.67945 -0.305054)
			(end -0.12065 -0.305054)
			(stroke
				(width 0.1)
				(type default)
			)
			(layer "F.Fab")
		)
		(pad "1" smd circle
			(at -0.40005 0 180)
			(size 0 0)
			(layers "F.Cu" "F.Mask" "F.Paste")
			(net "P3V3_AUX")
		)
		(pad "2" smd circle
			(at 0.40005 0 180)
			(size 0 0)
			(layers "F.Cu" "F.Mask" "F.Paste")
			(net "P0V9_RETIMER_CPU0_CFP")
		)
	)
	(footprint ""
		(layer "F.Cu")
		(at 407.452322 -163.382198)
		(property "Reference" "PR359"
			(at 0 0 0)
			(layer "F.SilkS")
			(hide yes)
			(effects
				(font
					(size 1.27 1.27)
				)
			)
		)
		(property "Value" ""
			(at 0 0 0)
			(layer "F.Fab")
			(effects
				(font
					(size 1.27 1.27)
				)
			)
		)
		(duplicate_pad_numbers_are_jumpers no)
		(fp_line
			(start -0.7874 -0.4064)
			(end 0.7874 -0.4064)
			(stroke
				(width 0.1524)
				(type default)
			)
			(layer "F.SilkS")
		)
		(fp_line
			(start -0.7874 0.4064)
			(end -0.7874 -0.4064)
			(stroke
				(width 0.1524)
				(type default)
			)
			(layer "F.SilkS")
		)
		(fp_line
			(start 0.7874 -0.4064)
			(end 0.7874 0.4064)
			(stroke
				(width 0.1524)
				(type default)
			)
			(layer "F.SilkS")
		)
		(fp_line
			(start 0.7874 0.4064)
			(end -0.7874 0.4064)
			(stroke
				(width 0.1524)
				(type default)
			)
			(layer "F.SilkS")
		)
		(fp_line
			(start -0.67945 -0.305054)
			(end -0.12065 -0.305054)
			(stroke
				(width 0.1)
				(type default)
			)
			(layer "F.Fab")
		)
		(fp_line
			(start -0.67945 0.3048)
			(end -0.67945 -0.305054)
			(stroke
				(width 0.1)
				(type default)
			)
			(layer "F.Fab")
		)
		(fp_line
			(start -0.12065 -0.305054)
			(end -0.12065 -0.2794)
			(stroke
				(width 0.1)
				(type default)
			)
			(layer "F.Fab")
		)
		(fp_line
			(start -0.12065 -0.2794)
			(end 0.12065 -0.2794)
			(stroke
				(width 0.1)
				(type default)
			)
			(layer "F.Fab")
		)
		(fp_line
			(start -0.12065 0.2794)
			(end -0.12065 0.3048)
			(stroke
				(width 0.1)
				(type default)
			)
			(layer "F.Fab")
		)
		(fp_line
			(start -0.12065 0.3048)
			(end -0.67945 0.3048)
			(stroke
				(width 0.1)
				(type default)
			)
			(layer "F.Fab")
		)
		(fp_line
			(start 0.120396 0.2794)
			(end -0.12065 0.2794)
			(stroke
				(width 0.1)
				(type default)
			)
			(layer "F.Fab")
		)
		(fp_line
			(start 0.120396 0.3048)
			(end 0.120396 0.2794)
			(stroke
				(width 0.1)
				(type default)
			)
			(layer "F.Fab")
		)
		(fp_line
			(start 0.12065 -0.3048)
			(end 0.67945 -0.3048)
			(stroke
				(width 0.1)
				(type default)
			)
			(layer "F.Fab")
		)
		(fp_line
			(start 0.12065 -0.2794)
			(end 0.12065 -0.3048)
			(stroke
				(width 0.1)
				(type default)
			)
			(layer "F.Fab")
		)
		(fp_line
			(start 0.67945 -0.3048)
			(end 0.67945 0.3048)
			(stroke
				(width 0.1)
				(type default)
			)
			(layer "F.Fab")
		)
		(fp_line
			(start 0.67945 0.3048)
			(end 0.120396 0.3048)
			(stroke
				(width 0.1)
				(type default)
			)
			(layer "F.Fab")
		)
		(pad "1" smd circle
			(at -0.40005 0)
			(size 0 0)
			(layers "F.Cu" "F.Mask" "F.Paste")
			(net "GND")
		)
		(pad "2" smd circle
			(at 0.40005 0)
			(size 0 0)
			(layers "F.Cu" "F.Mask" "F.Paste")
			(net "PVDDCR_SOC_P0_LSET2")
		)
	)
	(footprint ""
		(layer "F.Cu")
		(at 149.649434 -321.733672 180)
		(property "Reference" "R373"
			(at 0 0 180)
			(layer "F.SilkS")
			(hide yes)
			(effects
				(font
					(size 1.27 1.27)
				)
			)
		)
		(property "Value" ""
			(at 0 0 180)
			(layer "F.Fab")
			(effects
				(font
					(size 1.27 1.27)
				)
			)
		)
		(duplicate_pad_numbers_are_jumpers no)
		(fp_line
			(start 0.7874 0.4064)
			(end -0.7874 0.4064)
			(stroke
				(width 0.1524)
				(type default)
			)
			(layer "F.SilkS")
		)
		(fp_line
			(start 0.7874 -0.4064)
			(end 0.7874 0.4064)
			(stroke
				(width 0.1524)
				(type default)
			)
			(layer "F.SilkS")
		)
		(fp_line
			(start -0.7874 0.4064)
			(end -0.7874 -0.4064)
			(stroke
				(width 0.1524)
				(type default)
			)
			(layer "F.SilkS")
		)
		(fp_line
			(start -0.7874 -0.4064)
			(end 0.7874 -0.4064)
			(stroke
				(width 0.1524)
				(type default)
			)
			(layer "F.SilkS")
		)
		(fp_line
			(start 0.67945 0.3048)
			(end 0.120396 0.3048)
			(stroke
				(width 0.1)
				(type default)
			)
			(layer "F.Fab")
		)
		(fp_line
			(start 0.67945 -0.3048)
			(end 0.67945 0.3048)
			(stroke
				(width 0.1)
				(type default)
			)
			(layer "F.Fab")
		)
		(fp_line
			(start 0.12065 -0.2794)
			(end 0.12065 -0.3048)
			(stroke
				(width 0.1)
				(type default)
			)
			(layer "F.Fab")
		)
		(fp_line
			(start 0.12065 -0.3048)
			(end 0.67945 -0.3048)
			(stroke
				(width 0.1)
				(type default)
			)
			(layer "F.Fab")
		)
		(fp_line
			(start 0.120396 0.3048)
			(end 0.120396 0.2794)
			(stroke
				(width 0.1)
				(type default)
			)
			(layer "F.Fab")
		)
		(fp_line
			(start 0.120396 0.2794)
			(end -0.12065 0.2794)
			(stroke
				(width 0.1)
				(type default)
			)
			(layer "F.Fab")
		)
		(fp_line
			(start -0.12065 0.3048)
			(end -0.67945 0.3048)
			(stroke
				(width 0.1)
				(type default)
			)
			(layer "F.Fab")
		)
		(fp_line
			(start -0.12065 0.2794)
			(end -0.12065 0.3048)
			(stroke
				(width 0.1)
				(type default)
			)
			(layer "F.Fab")
		)
		(fp_line
			(start -0.12065 -0.2794)
			(end 0.12065 -0.2794)
			(stroke
				(width 0.1)
				(type default)
			)
			(layer "F.Fab")
		)
		(fp_line
			(start -0.12065 -0.305054)
			(end -0.12065 -0.2794)
			(stroke
				(width 0.1)
				(type default)
			)
			(layer "F.Fab")
		)
		(fp_line
			(start -0.67945 0.3048)
			(end -0.67945 -0.305054)
			(stroke
				(width 0.1)
				(type default)
			)
			(layer "F.Fab")
		)
		(fp_line
			(start -0.67945 -0.305054)
			(end -0.12065 -0.305054)
			(stroke
				(width 0.1)
				(type default)
			)
			(layer "F.Fab")
		)
		(pad "1" smd circle
			(at -0.40005 0 180)
			(size 0 0)
			(layers "F.Cu" "F.Mask" "F.Paste")
			(net "P1V5_BAT")
		)
		(pad "2" smd circle
			(at 0.40005 0 180)
			(size 0 0)
			(layers "F.Cu" "F.Mask" "F.Paste")
			(net "CPU1_VDDBT_RTC_G")
		)
	)
	(footprint ""
		(layer "F.Cu")
		(at 174.635922 -24.601932)
		(property "Reference" "PR4014"
			(at 0 0 0)
			(layer "F.SilkS")
			(hide yes)
			(effects
				(font
					(size 1.27 1.27)
				)
			)
		)
		(property "Value" ""
			(at 0 0 0)
			(layer "F.Fab")
			(effects
				(font
					(size 1.27 1.27)
				)
			)
		)
		(duplicate_pad_numbers_are_jumpers no)
		(fp_line
			(start -1.2954 -0.5842)
			(end 1.2954 -0.5842)
			(stroke
				(width 0.1524)
				(type default)
			)
			(layer "F.SilkS")
		)
		(fp_line
			(start -1.2954 0.5842)
			(end -1.2954 -0.5842)
			(stroke
				(width 0.1524)
				(type default)
			)
			(layer "F.SilkS")
		)
		(fp_line
			(start 1.2954 -0.5842)
			(end 1.2954 0.5842)
			(stroke
				(width 0.1524)
				(type default)
			)
			(layer "F.SilkS")
		)
		(fp_line
			(start 1.2954 0.5842)
			(end -1.2954 0.5842)
			(stroke
				(width 0.1524)
				(type default)
			)
			(layer "F.SilkS")
		)
		(fp_line
			(start -1.1938 -0.406654)
			(end -0.8636 -0.406654)
			(stroke
				(width 0.1)
				(type default)
			)
			(layer "F.Fab")
		)
		(fp_line
			(start -1.1938 0.4064)
			(end -1.1938 -0.406654)
			(stroke
				(width 0.1)
				(type default)
			)
			(layer "F.Fab")
		)
		(fp_line
			(start -0.8636 -0.4572)
			(end 0.8636 -0.4572)
			(stroke
				(width 0.1)
				(type default)
			)
			(layer "F.Fab")
		)
		(fp_line
			(start -0.8636 -0.406654)
			(end -0.8636 -0.4572)
			(stroke
				(width 0.1)
				(type default)
			)
			(layer "F.Fab")
		)
		(fp_line
			(start -0.8636 0.4064)
			(end -1.1938 0.4064)
			(stroke
				(width 0.1)
				(type default)
			)
			(layer "F.Fab")
		)
		(fp_line
			(start -0.8636 0.4318)
			(end -0.8636 0.4064)
			(stroke
				(width 0.1)
				(type default)
			)
			(layer "F.Fab")
		)
		(fp_line
			(start -0.8636 0.4572)
			(end -0.8636 0.4318)
			(stroke
				(width 0.1)
				(type default)
			)
			(layer "F.Fab")
		)
		(fp_line
			(start 0.8636 -0.4572)
			(end 0.8636 -0.406654)
			(stroke
				(width 0.1)
				(type default)
			)
			(layer "F.Fab")
		)
		(fp_line
			(start 0.8636 -0.406654)
			(end 1.1938 -0.406654)
			(stroke
				(width 0.1)
				(type default)
			)
			(layer "F.Fab")
		)
		(fp_line
			(start 0.8636 0.4064)
			(end 0.8636 0.4572)
			(stroke
				(width 0.1)
				(type default)
			)
			(layer "F.Fab")
		)
		(fp_line
			(start 0.8636 0.4572)
			(end -0.8636 0.4572)
			(stroke
				(width 0.1)
				(type default)
			)
			(layer "F.Fab")
		)
		(fp_line
			(start 1.1938 -0.406654)
			(end 1.1938 0.4064)
			(stroke
				(width 0.1)
				(type default)
			)
			(layer "F.Fab")
		)
		(fp_line
			(start 1.1938 0.4064)
			(end 0.8636 0.4064)
			(stroke
				(width 0.1)
				(type default)
			)
			(layer "F.Fab")
		)
		(pad "1" smd rect
			(at -0.7366 0 270)
			(size 0.7112 0.8128)
			(layers "F.Cu" "F.Mask" "F.Paste")
			(net "P12V_AUX")
		)
		(pad "2" smd rect
			(at 0.7366 0 270)
			(size 0.7112 0.8128)
			(layers "F.Cu" "F.Mask" "F.Paste")
			(net "P12V_SCM_AVIN_PD")
		)
	)
	(footprint ""
		(layer "F.Cu")
		(at 170.2308 -386.3848)
		(property "Reference" "C367"
			(at 0 0 0)
			(layer "F.SilkS")
			(hide yes)
			(effects
				(font
					(size 1.27 1.27)
				)
			)
		)
		(property "Value" ""
			(at 0 0 0)
			(layer "F.Fab")
			(effects
				(font
					(size 1.27 1.27)
				)
			)
		)
		(duplicate_pad_numbers_are_jumpers no)
		(fp_line
			(start -1.524 -0.762)
			(end 1.524 -0.762)
			(stroke
				(width 0.1524)
				(type default)
			)
			(layer "F.SilkS")
		)
		(fp_line
			(start -1.524 0.762)
			(end -1.524 -0.762)
			(stroke
				(width 0.1524)
				(type default)
			)
			(layer "F.SilkS")
		)
		(fp_line
			(start 1.524 -0.762)
			(end 1.524 0.762)
			(stroke
				(width 0.1524)
				(type default)
			)
			(layer "F.SilkS")
		)
		(fp_line
			(start 1.524 0.762)
			(end -1.524 0.762)
			(stroke
				(width 0.1524)
				(type default)
			)
			(layer "F.SilkS")
		)
		(fp_line
			(start -1.1049 -0.724916)
			(end -1.1049 0.724916)
			(stroke
				(width 0.1)
				(type default)
			)
			(layer "F.Fab")
		)
		(fp_line
			(start -1.1049 0.724916)
			(end 1.1049 0.724916)
			(stroke
				(width 0.1)
				(type default)
			)
			(layer "F.Fab")
		)
		(fp_line
			(start 1.1049 -0.724916)
			(end -1.1049 -0.724916)
			(stroke
				(width 0.1)
				(type default)
			)
			(layer "F.Fab")
		)
		(fp_line
			(start 1.1049 0.724916)
			(end 1.1049 -0.724916)
			(stroke
				(width 0.1)
				(type default)
			)
			(layer "F.Fab")
		)
		(pad "1" smd rect
			(at -0.889 0 180)
			(size 1.016 1.27)
			(layers "F.Cu" "F.Mask" "F.Paste")
			(net "P1V8_CPU1_RT2_1A")
		)
		(pad "2" smd rect
			(at 0.889 0 180)
			(size 1.016 1.27)
			(layers "F.Cu" "F.Mask" "F.Paste")
			(net "GND")
		)
	)
	(footprint ""
		(layer "F.Cu")
		(at 120.396 -435.483)
		(property "Reference" "R3495"
			(at 0 0 0)
			(layer "F.SilkS")
			(hide yes)
			(effects
				(font
					(size 1.27 1.27)
				)
			)
		)
		(property "Value" ""
			(at 0 0 0)
			(layer "F.Fab")
			(effects
				(font
					(size 1.27 1.27)
				)
			)
		)
		(duplicate_pad_numbers_are_jumpers no)
		(fp_line
			(start -0.7874 -0.4064)
			(end 0.7874 -0.4064)
			(stroke
				(width 0.1524)
				(type default)
			)
			(layer "F.SilkS")
		)
		(fp_line
			(start -0.7874 0.4064)
			(end -0.7874 -0.4064)
			(stroke
				(width 0.1524)
				(type default)
			)
			(layer "F.SilkS")
		)
		(fp_line
			(start 0.7874 -0.4064)
			(end 0.7874 0.4064)
			(stroke
				(width 0.1524)
				(type default)
			)
			(layer "F.SilkS")
		)
		(fp_line
			(start 0.7874 0.4064)
			(end -0.7874 0.4064)
			(stroke
				(width 0.1524)
				(type default)
			)
			(layer "F.SilkS")
		)
		(fp_line
			(start -0.67945 -0.305054)
			(end -0.12065 -0.305054)
			(stroke
				(width 0.1)
				(type default)
			)
			(layer "F.Fab")
		)
		(fp_line
			(start -0.67945 0.3048)
			(end -0.67945 -0.305054)
			(stroke
				(width 0.1)
				(type default)
			)
			(layer "F.Fab")
		)
		(fp_line
			(start -0.12065 -0.305054)
			(end -0.12065 -0.2794)
			(stroke
				(width 0.1)
				(type default)
			)
			(layer "F.Fab")
		)
		(fp_line
			(start -0.12065 -0.2794)
			(end 0.12065 -0.2794)
			(stroke
				(width 0.1)
				(type default)
			)
			(layer "F.Fab")
		)
		(fp_line
			(start -0.12065 0.2794)
			(end -0.12065 0.3048)
			(stroke
				(width 0.1)
				(type default)
			)
			(layer "F.Fab")
		)
		(fp_line
			(start -0.12065 0.3048)
			(end -0.67945 0.3048)
			(stroke
				(width 0.1)
				(type default)
			)
			(layer "F.Fab")
		)
		(fp_line
			(start 0.120396 0.2794)
			(end -0.12065 0.2794)
			(stroke
				(width 0.1)
				(type default)
			)
			(layer "F.Fab")
		)
		(fp_line
			(start 0.120396 0.3048)
			(end 0.120396 0.2794)
			(stroke
				(width 0.1)
				(type default)
			)
			(layer "F.Fab")
		)
		(fp_line
			(start 0.12065 -0.3048)
			(end 0.67945 -0.3048)
			(stroke
				(width 0.1)
				(type default)
			)
			(layer "F.Fab")
		)
		(fp_line
			(start 0.12065 -0.2794)
			(end 0.12065 -0.3048)
			(stroke
				(width 0.1)
				(type default)
			)
			(layer "F.Fab")
		)
		(fp_line
			(start 0.67945 -0.3048)
			(end 0.67945 0.3048)
			(stroke
				(width 0.1)
				(type default)
			)
			(layer "F.Fab")
		)
		(fp_line
			(start 0.67945 0.3048)
			(end 0.120396 0.3048)
			(stroke
				(width 0.1)
				(type default)
			)
			(layer "F.Fab")
		)
		(pad "1" smd circle
			(at -0.40005 0)
			(size 0 0)
			(layers "F.Cu" "F.Mask" "F.Paste")
			(net "GPU_FPGA_EROT_RECOV_BUF_R_N")
		)
		(pad "2" smd circle
			(at 0.40005 0)
			(size 0 0)
			(layers "F.Cu" "F.Mask" "F.Paste")
			(net "GND")
		)
	)
	(footprint ""
		(layer "F.Cu")
		(at 296.385742 -397.4084 -90)
		(property "Reference" "R974"
			(at 0 0 270)
			(layer "F.SilkS")
			(hide yes)
			(effects
				(font
					(size 1.27 1.27)
				)
			)
		)
		(property "Value" ""
			(at 0 0 270)
			(layer "F.Fab")
			(effects
				(font
					(size 1.27 1.27)
				)
			)
		)
		(duplicate_pad_numbers_are_jumpers no)
		(fp_line
			(start -0.32512 0.175006)
			(end -0.32512 -0.175006)
			(stroke
				(width 0.1)
				(type default)
			)
			(layer "F.Fab")
		)
		(fp_line
			(start 0.32512 0.175006)
			(end -0.32512 0.175006)
			(stroke
				(width 0.1)
				(type default)
			)
			(layer "F.Fab")
		)
		(fp_line
			(start -0.32512 -0.175006)
			(end 0.32512 -0.175006)
			(stroke
				(width 0.1)
				(type default)
			)
			(layer "F.Fab")
		)
		(fp_line
			(start 0.32512 -0.175006)
			(end 0.32512 0.175006)
			(stroke
				(width 0.1)
				(type default)
			)
			(layer "F.Fab")
		)
		(pad "1" smd rect
			(at -0.2667 0 270)
			(size 0.3048 0.381)
			(layers "F.Cu" "F.Mask" "F.Paste")
			(net "P1V8_CPU0_RT_1D")
		)
		(pad "2" smd rect
			(at 0.2667 0 90)
			(size 0.3048 0.381)
			(layers "F.Cu" "F.Mask" "F.Paste")
			(net "RST_RT_CPU0_P0_RESET_R_N")
		)
	)
)
